(kicad_pcb
	(version 20260206)
	(generator "pcbnew")
	(generator_version "10.0")
	(general
		(thickness 1.6)
		(legacy_teardrops no)
	)
	(paper "A4")
	(title_block
		(title "01162023_DA0F0TEBIF0_F0T_Expander_BD_F_brd_V02_OCP.brd")
		(comment 1 "Grand Teton / footprint 5834 of 9728 (J23), pads 1-109 of 179")
	)
	(layers
		(0 "F.Cu" signal "TOP")
		(4 "In1.Cu" signal "GND")
		(6 "In2.Cu" signal "VCC")
		(8 "In3.Cu" signal "VCC1")
		(10 "In4.Cu" signal "GND1")
		(12 "In5.Cu" signal "IN1")
		(14 "In6.Cu" signal "GND2")
		(16 "In7.Cu" signal "IN2")
		(18 "In8.Cu" signal "GND3")
		(20 "In9.Cu" signal "IN3")
		(22 "In10.Cu" signal "GND4")
		(24 "In11.Cu" signal "IN4")
		(26 "In12.Cu" signal "GND5")
		(28 "In13.Cu" signal "IN5")
		(30 "In14.Cu" signal "GND6")
		(32 "In15.Cu" signal "IN6")
		(34 "In16.Cu" signal "GND7")
		(2 "B.Cu" signal "BOTTOM")
		(9 "F.Adhes" user "F.Adhesive")
		(11 "B.Adhes" user "B.Adhesive")
		(13 "F.Paste" user "Package Geometry/Pastemask Top")
		(15 "B.Paste" user "Package Geometry/Pastemask Bottom")
		(5 "F.SilkS" user "Ref Des/Silkscreen Top")
		(7 "B.SilkS" user "Ref Des/Silkscreen Bottom")
		(1 "F.Mask" user "Board Geometry/Soldermask Top")
		(3 "B.Mask" user "Board Geometry/Soldermask Bottom")
		(17 "Dwgs.User" user "User.Drawings")
		(19 "Cmts.User" user "User.Comments")
		(21 "Eco1.User" user "User.Eco1")
		(23 "Eco2.User" user "User.Eco2")
		(25 "Edge.Cuts" user "Board Geometry/Outline")
		(27 "Margin" user)
		(31 "F.CrtYd" user "Package Geometry/Place Bound Top")
		(29 "B.CrtYd" user "Package Geometry/Place Bound Bottom")
		(35 "F.Fab" user "Ref Des/Assembly Top")
		(33 "B.Fab" user "Ref Des/Assembly Bottom")
	)
	(footprint ""
		(layer "F.Cu")
		(at 188.079888 -127.700024 180)
		(property "Reference" "J23"
			(at 5.351018 -34.634424 90)
			(unlocked yes)
			(layer "F.SilkS")
			(effects
				(font
					(size 0.7874 0.5842)
					(thickness 0.1524)
				)
				(justify left)
			)
		)
		(property "Value" ""
			(at 0 0 180)
			(layer "F.Fab")
			(effects
				(font
					(size 1.27 1.27)
				)
			)
		)
		(duplicate_pad_numbers_are_jumpers no)
		(pad "" np_thru_hole circle
			(at -0.727456 -32.485076 180)
			(size 1.1176 1.1176)
			(drill 1.1176)
			(layers "*.Cu" "*.Mask")
			(clearance 0.381)
			(thermal_gap 0.381)
		)
		(pad "" np_thru_hole circle
			(at 1.022604 32.485076 180)
			(size 1.1176 1.1176)
			(drill 1.1176)
			(layers "*.Cu" "*.Mask")
			(clearance 0.381)
			(thermal_gap 0.381)
		)
		(pad "A1" smd rect
			(at 3.322574 -18.465038 90)
			(size 0.3556 1.2192)
			(layers "F.Cu" "F.Mask" "F.Paste")
			(net "GND")
		)
		(pad "A2" smd rect
			(at 3.322574 -17.86509 90)
			(size 0.3556 1.2192)
			(layers "F.Cu" "F.Mask" "F.Paste")
			(net "GND")
		)
		(pad "A3" smd rect
			(at 3.322574 -17.264888 90)
			(size 0.3556 1.2192)
			(layers "F.Cu" "F.Mask" "F.Paste")
			(net "GND")
		)
		(pad "A4" smd rect
			(at 3.322574 -16.66494 90)
			(size 0.3556 1.2192)
			(layers "F.Cu" "F.Mask" "F.Paste")
			(net "GND")
		)
		(pad "A5" smd rect
			(at 3.322574 -16.064992 90)
			(size 0.3556 1.2192)
			(layers "F.Cu" "F.Mask" "F.Paste")
			(net "GND")
		)
		(pad "A6" smd rect
			(at 3.322574 -15.465044 90)
			(size 0.3556 1.2192)
			(layers "F.Cu" "F.Mask" "F.Paste")
			(net "GND")
		)
		(pad "A7" smd rect
			(at 3.322574 -14.865096 90)
			(size 0.3556 1.2192)
			(layers "F.Cu" "F.Mask" "F.Paste")
			(net "SMB_NIC3_R_SCL")
		)
		(pad "A8" smd rect
			(at 3.322574 -14.264894 90)
			(size 0.3556 1.2192)
			(layers "F.Cu" "F.Mask" "F.Paste")
			(net "SMB_NIC3_R_SDA")
		)
		(pad "A9" smd rect
			(at 3.322574 -13.664946 90)
			(size 0.3556 1.2192)
			(layers "F.Cu" "F.Mask" "F.Paste")
			(net "RST_SMB_NIC3_MUX_ISO_R_N")
		)
		(pad "A10" smd rect
			(at 3.322574 -13.064998 90)
			(size 0.3556 1.2192)
			(layers "F.Cu" "F.Mask" "F.Paste")
			(net "GND")
		)
		(pad "A11" smd rect
			(at 3.322574 -12.46505 90)
			(size 0.3556 1.2192)
			(layers "F.Cu" "F.Mask" "F.Paste")
			(net "RST_NIC3_PERST1_R_N")
		)
		(pad "A12" smd rect
			(at 3.322574 -11.865102 90)
			(size 0.3556 1.2192)
			(layers "F.Cu" "F.Mask" "F.Paste")
			(net "PRSNTB2_NIC3_N")
		)
		(pad "A13" smd rect
			(at 3.322574 -11.2649 90)
			(size 0.3556 1.2192)
			(layers "F.Cu" "F.Mask" "F.Paste")
			(net "GND")
		)
		(pad "A14" smd rect
			(at 3.322574 -10.664952 90)
			(size 0.3556 1.2192)
			(layers "F.Cu" "F.Mask" "F.Paste")
			(net "Net_2614")
		)
		(pad "A15" smd rect
			(at 3.322574 -10.065004 90)
			(size 0.3556 1.2192)
			(layers "F.Cu" "F.Mask" "F.Paste")
			(net "Net_2617")
		)
		(pad "A16" smd rect
			(at 3.322574 -9.465056 90)
			(size 0.3556 1.2192)
			(layers "F.Cu" "F.Mask" "F.Paste")
			(net "GND")
		)
		(pad "A17" smd rect
			(at 3.322574 -8.865108 90)
			(size 0.3556 1.2192)
			(layers "F.Cu" "F.Mask" "F.Paste")
			(net "P5E_PEX1_STN0_RX_DN<0>")
		)
		(pad "A18" smd rect
			(at 3.322574 -8.264906 90)
			(size 0.3556 1.2192)
			(layers "F.Cu" "F.Mask" "F.Paste")
			(net "P5E_PEX1_STN0_RX_DP<0>")
		)
		(pad "A19" smd rect
			(at 3.322574 -7.664958 90)
			(size 0.3556 1.2192)
			(layers "F.Cu" "F.Mask" "F.Paste")
			(net "GND")
		)
		(pad "A20" smd rect
			(at 3.322574 -7.06501 90)
			(size 0.3556 1.2192)
			(layers "F.Cu" "F.Mask" "F.Paste")
			(net "P5E_PEX1_STN0_RX_DN<1>")
		)
		(pad "A21" smd rect
			(at 3.322574 -6.465062 90)
			(size 0.3556 1.2192)
			(layers "F.Cu" "F.Mask" "F.Paste")
			(net "P5E_PEX1_STN0_RX_DP<1>")
		)
		(pad "A22" smd rect
			(at 3.322574 -5.865114 90)
			(size 0.3556 1.2192)
			(layers "F.Cu" "F.Mask" "F.Paste")
			(net "GND")
		)
		(pad "A23" smd rect
			(at 3.322574 -5.264912 90)
			(size 0.3556 1.2192)
			(layers "F.Cu" "F.Mask" "F.Paste")
			(net "P5E_PEX1_STN0_RX_DN<2>")
		)
		(pad "A24" smd rect
			(at 3.322574 -4.664964 90)
			(size 0.3556 1.2192)
			(layers "F.Cu" "F.Mask" "F.Paste")
			(net "P5E_PEX1_STN0_RX_DP<2>")
		)
		(pad "A25" smd rect
			(at 3.322574 -4.065016 90)
			(size 0.3556 1.2192)
			(layers "F.Cu" "F.Mask" "F.Paste")
			(net "GND")
		)
		(pad "A26" smd rect
			(at 3.322574 -3.465068 90)
			(size 0.3556 1.2192)
			(layers "F.Cu" "F.Mask" "F.Paste")
			(net "P5E_PEX1_STN0_RX_DN<3>")
		)
		(pad "A27" smd rect
			(at 3.322574 -2.86512 90)
			(size 0.3556 1.2192)
			(layers "F.Cu" "F.Mask" "F.Paste")
			(net "P5E_PEX1_STN0_RX_DP<3>")
		)
		(pad "A28" smd rect
			(at 3.322574 -2.264918 90)
			(size 0.3556 1.2192)
			(layers "F.Cu" "F.Mask" "F.Paste")
			(net "GND")
		)
		(pad "A29" smd rect
			(at 3.322574 1.74498 90)
			(size 0.3556 1.2192)
			(layers "F.Cu" "F.Mask" "F.Paste")
			(net "GND")
		)
		(pad "A30" smd rect
			(at 3.322574 2.344928 90)
			(size 0.3556 1.2192)
			(layers "F.Cu" "F.Mask" "F.Paste")
			(net "P5E_PEX1_STN0_RX_DN<4>")
		)
		(pad "A31" smd rect
			(at 3.322574 2.944876 90)
			(size 0.3556 1.2192)
			(layers "F.Cu" "F.Mask" "F.Paste")
			(net "P5E_PEX1_STN0_RX_DP<4>")
		)
		(pad "A32" smd rect
			(at 3.322574 3.545078 90)
			(size 0.3556 1.2192)
			(layers "F.Cu" "F.Mask" "F.Paste")
			(net "GND")
		)
		(pad "A33" smd rect
			(at 3.322574 4.145026 90)
			(size 0.3556 1.2192)
			(layers "F.Cu" "F.Mask" "F.Paste")
			(net "P5E_PEX1_STN0_RX_DN<5>")
		)
		(pad "A34" smd rect
			(at 3.322574 4.744974 90)
			(size 0.3556 1.2192)
			(layers "F.Cu" "F.Mask" "F.Paste")
			(net "P5E_PEX1_STN0_RX_DP<5>")
		)
		(pad "A35" smd rect
			(at 3.322574 5.344922 90)
			(size 0.3556 1.2192)
			(layers "F.Cu" "F.Mask" "F.Paste")
			(net "GND")
		)
		(pad "A36" smd rect
			(at 3.322574 5.945124 90)
			(size 0.3556 1.2192)
			(layers "F.Cu" "F.Mask" "F.Paste")
			(net "P5E_PEX1_STN0_RX_DN<6>")
		)
		(pad "A37" smd rect
			(at 3.322574 6.545072 90)
			(size 0.3556 1.2192)
			(layers "F.Cu" "F.Mask" "F.Paste")
			(net "P5E_PEX1_STN0_RX_DP<6>")
		)
		(pad "A38" smd rect
			(at 3.322574 7.14502 90)
			(size 0.3556 1.2192)
			(layers "F.Cu" "F.Mask" "F.Paste")
			(net "GND")
		)
		(pad "A39" smd rect
			(at 3.322574 7.744968 90)
			(size 0.3556 1.2192)
			(layers "F.Cu" "F.Mask" "F.Paste")
			(net "P5E_PEX1_STN0_RX_DN<7>")
		)
		(pad "A40" smd rect
			(at 3.322574 8.344916 90)
			(size 0.3556 1.2192)
			(layers "F.Cu" "F.Mask" "F.Paste")
			(net "P5E_PEX1_STN0_RX_DP<7>")
		)
		(pad "A41" smd rect
			(at 3.322574 8.945118 90)
			(size 0.3556 1.2192)
			(layers "F.Cu" "F.Mask" "F.Paste")
			(net "GND")
		)
		(pad "A42" smd rect
			(at 3.322574 9.545066 90)
			(size 0.3556 1.2192)
			(layers "F.Cu" "F.Mask" "F.Paste")
			(net "PRSNTB1_NIC3_N")
		)
		(pad "A43" smd rect
			(at 3.322574 14.454886 90)
			(size 0.3556 1.2192)
			(layers "F.Cu" "F.Mask" "F.Paste")
			(net "GND")
		)
		(pad "A44" smd rect
			(at 3.322574 15.055088 90)
			(size 0.3556 1.2192)
			(layers "F.Cu" "F.Mask" "F.Paste")
			(net "P5E_PEX1_STN0_RX_DN<8>")
		)
		(pad "A45" smd rect
			(at 3.322574 15.655036 90)
			(size 0.3556 1.2192)
			(layers "F.Cu" "F.Mask" "F.Paste")
			(net "P5E_PEX1_STN0_RX_DP<8>")
		)
		(pad "A46" smd rect
			(at 3.322574 16.254984 90)
			(size 0.3556 1.2192)
			(layers "F.Cu" "F.Mask" "F.Paste")
			(net "GND")
		)
		(pad "A47" smd rect
			(at 3.322574 16.854932 90)
			(size 0.3556 1.2192)
			(layers "F.Cu" "F.Mask" "F.Paste")
			(net "P5E_PEX1_STN0_RX_DN<9>")
		)
		(pad "A48" smd rect
			(at 3.322574 17.45488 90)
			(size 0.3556 1.2192)
			(layers "F.Cu" "F.Mask" "F.Paste")
			(net "P5E_PEX1_STN0_RX_DP<9>")
		)
		(pad "A49" smd rect
			(at 3.322574 18.055082 90)
			(size 0.3556 1.2192)
			(layers "F.Cu" "F.Mask" "F.Paste")
			(net "GND")
		)
		(pad "A50" smd rect
			(at 3.322574 18.65503 90)
			(size 0.3556 1.2192)
			(layers "F.Cu" "F.Mask" "F.Paste")
			(net "P5E_PEX1_STN0_RX_DN<10>")
		)
		(pad "A51" smd rect
			(at 3.322574 19.254978 90)
			(size 0.3556 1.2192)
			(layers "F.Cu" "F.Mask" "F.Paste")
			(net "P5E_PEX1_STN0_RX_DP<10>")
		)
		(pad "A52" smd rect
			(at 3.322574 19.854926 90)
			(size 0.3556 1.2192)
			(layers "F.Cu" "F.Mask" "F.Paste")
			(net "GND")
		)
		(pad "A53" smd rect
			(at 3.322574 20.455128 90)
			(size 0.3556 1.2192)
			(layers "F.Cu" "F.Mask" "F.Paste")
			(net "P5E_PEX1_STN0_RX_DN<11>")
		)
		(pad "A54" smd rect
			(at 3.322574 21.055076 90)
			(size 0.3556 1.2192)
			(layers "F.Cu" "F.Mask" "F.Paste")
			(net "P5E_PEX1_STN0_RX_DP<11>")
		)
		(pad "A55" smd rect
			(at 3.322574 21.655024 90)
			(size 0.3556 1.2192)
			(layers "F.Cu" "F.Mask" "F.Paste")
			(net "GND")
		)
		(pad "A56" smd rect
			(at 3.322574 22.254972 90)
			(size 0.3556 1.2192)
			(layers "F.Cu" "F.Mask" "F.Paste")
			(net "P5E_PEX1_STN0_RX_DN<12>")
		)
		(pad "A57" smd rect
			(at 3.322574 22.85492 90)
			(size 0.3556 1.2192)
			(layers "F.Cu" "F.Mask" "F.Paste")
			(net "P5E_PEX1_STN0_RX_DP<12>")
		)
		(pad "A58" smd rect
			(at 3.322574 23.455122 90)
			(size 0.3556 1.2192)
			(layers "F.Cu" "F.Mask" "F.Paste")
			(net "GND")
		)
		(pad "A59" smd rect
			(at 3.322574 24.05507 90)
			(size 0.3556 1.2192)
			(layers "F.Cu" "F.Mask" "F.Paste")
			(net "P5E_PEX1_STN0_RX_DN<13>")
		)
		(pad "A60" smd rect
			(at 3.322574 24.655018 90)
			(size 0.3556 1.2192)
			(layers "F.Cu" "F.Mask" "F.Paste")
			(net "P5E_PEX1_STN0_RX_DP<13>")
		)
		(pad "A61" smd rect
			(at 3.322574 25.254966 90)
			(size 0.3556 1.2192)
			(layers "F.Cu" "F.Mask" "F.Paste")
			(net "GND")
		)
		(pad "A62" smd rect
			(at 3.322574 25.854914 90)
			(size 0.3556 1.2192)
			(layers "F.Cu" "F.Mask" "F.Paste")
			(net "P5E_PEX1_STN0_RX_DN<14>")
		)
		(pad "A63" smd rect
			(at 3.322574 26.455116 90)
			(size 0.3556 1.2192)
			(layers "F.Cu" "F.Mask" "F.Paste")
			(net "P5E_PEX1_STN0_RX_DP<14>")
		)
		(pad "A64" smd rect
			(at 3.322574 27.055064 90)
			(size 0.3556 1.2192)
			(layers "F.Cu" "F.Mask" "F.Paste")
			(net "GND")
		)
		(pad "A65" smd rect
			(at 3.322574 27.655012 90)
			(size 0.3556 1.2192)
			(layers "F.Cu" "F.Mask" "F.Paste")
			(net "P5E_PEX1_STN0_RX_DN<15>")
		)
		(pad "A66" smd rect
			(at 3.322574 28.25496 90)
			(size 0.3556 1.2192)
			(layers "F.Cu" "F.Mask" "F.Paste")
			(net "P5E_PEX1_STN0_RX_DP<15>")
		)
		(pad "A67" smd rect
			(at 3.322574 28.854908 90)
			(size 0.3556 1.2192)
			(layers "F.Cu" "F.Mask" "F.Paste")
			(net "GND")
		)
		(pad "A68" smd rect
			(at 3.322574 29.45511 90)
			(size 0.3556 1.2192)
			(layers "F.Cu" "F.Mask" "F.Paste")
			(net "Net_2622")
		)
		(pad "A69" smd rect
			(at 3.322574 30.055058 90)
			(size 0.3556 1.2192)
			(layers "F.Cu" "F.Mask" "F.Paste")
			(net "Net_2623")
		)
		(pad "A70" smd rect
			(at 3.322574 30.655006 90)
			(size 0.3556 1.2192)
			(layers "F.Cu" "F.Mask" "F.Paste")
			(net "NIC3_PWRBRK_R_N")
		)
		(pad "B1" smd rect
			(at -1.27762 -18.465038 90)
			(size 0.3556 1.2192)
			(layers "F.Cu" "F.Mask" "F.Paste")
			(net "P12V_NIC3")
		)
		(pad "B2" smd rect
			(at -1.27762 -17.86509 90)
			(size 0.3556 1.2192)
			(layers "F.Cu" "F.Mask" "F.Paste")
			(net "P12V_NIC3")
		)
		(pad "B3" smd rect
			(at -1.27762 -17.264888 90)
			(size 0.3556 1.2192)
			(layers "F.Cu" "F.Mask" "F.Paste")
			(net "P12V_NIC3")
		)
		(pad "B4" smd rect
			(at -1.27762 -16.66494 90)
			(size 0.3556 1.2192)
			(layers "F.Cu" "F.Mask" "F.Paste")
			(net "P12V_NIC3")
		)
		(pad "B5" smd rect
			(at -1.27762 -16.064992 90)
			(size 0.3556 1.2192)
			(layers "F.Cu" "F.Mask" "F.Paste")
			(net "P12V_NIC3")
		)
		(pad "B6" smd rect
			(at -1.27762 -15.465044 90)
			(size 0.3556 1.2192)
			(layers "F.Cu" "F.Mask" "F.Paste")
			(net "P12V_NIC3")
		)
		(pad "B7" smd rect
			(at -1.27762 -14.865096 90)
			(size 0.3556 1.2192)
			(layers "F.Cu" "F.Mask" "F.Paste")
			(net "NIC3_BIF0_N")
		)
		(pad "B8" smd rect
			(at -1.27762 -14.264894 90)
			(size 0.3556 1.2192)
			(layers "F.Cu" "F.Mask" "F.Paste")
			(net "NIC3_BIF1_N")
		)
		(pad "B9" smd rect
			(at -1.27762 -13.664946 90)
			(size 0.3556 1.2192)
			(layers "F.Cu" "F.Mask" "F.Paste")
			(net "NIC3_BIF2_N")
		)
		(pad "B10" smd rect
			(at -1.27762 -13.064998 90)
			(size 0.3556 1.2192)
			(layers "F.Cu" "F.Mask" "F.Paste")
			(net "RST_NIC3_PERST0_R_N")
		)
		(pad "B11" smd rect
			(at -1.27762 -12.46505 90)
			(size 0.3556 1.2192)
			(layers "F.Cu" "F.Mask" "F.Paste")
			(net "P3V3_NIC3")
		)
		(pad "B12" smd rect
			(at -1.27762 -11.865102 90)
			(size 0.3556 1.2192)
			(layers "F.Cu" "F.Mask" "F.Paste")
			(net "NIC3_AUX_PWR_EN_R")
		)
		(pad "B13" smd rect
			(at -1.27762 -11.2649 90)
			(size 0.3556 1.2192)
			(layers "F.Cu" "F.Mask" "F.Paste")
			(net "GND")
		)
		(pad "B14" smd rect
			(at -1.27762 -10.664952 90)
			(size 0.3556 1.2192)
			(layers "F.Cu" "F.Mask" "F.Paste")
			(net "CLK_100M_DB2000QL_NIC3_R_DN")
		)
		(pad "B15" smd rect
			(at -1.27762 -10.065004 90)
			(size 0.3556 1.2192)
			(layers "F.Cu" "F.Mask" "F.Paste")
			(net "CLK_100M_DB2000QL_NIC3_R_DP")
		)
		(pad "B16" smd rect
			(at -1.27762 -9.465056 90)
			(size 0.3556 1.2192)
			(layers "F.Cu" "F.Mask" "F.Paste")
			(net "GND")
		)
		(pad "B17" smd rect
			(at -1.27762 -8.865108 90)
			(size 0.3556 1.2192)
			(layers "F.Cu" "F.Mask" "F.Paste")
			(net "P5E_PEX1_STN0_TX_C_DN<0>")
		)
		(pad "B18" smd rect
			(at -1.27762 -8.264906 90)
			(size 0.3556 1.2192)
			(layers "F.Cu" "F.Mask" "F.Paste")
			(net "P5E_PEX1_STN0_TX_C_DP<0>")
		)
		(pad "B19" smd rect
			(at -1.27762 -7.664958 90)
			(size 0.3556 1.2192)
			(layers "F.Cu" "F.Mask" "F.Paste")
			(net "GND")
		)
		(pad "B20" smd rect
			(at -1.27762 -7.06501 90)
			(size 0.3556 1.2192)
			(layers "F.Cu" "F.Mask" "F.Paste")
			(net "P5E_PEX1_STN0_TX_C_DN<1>")
		)
		(pad "B21" smd rect
			(at -1.27762 -6.465062 90)
			(size 0.3556 1.2192)
			(layers "F.Cu" "F.Mask" "F.Paste")
			(net "P5E_PEX1_STN0_TX_C_DP<1>")
		)
		(pad "B22" smd rect
			(at -1.27762 -5.865114 90)
			(size 0.3556 1.2192)
			(layers "F.Cu" "F.Mask" "F.Paste")
			(net "GND")
		)
		(pad "B23" smd rect
			(at -1.27762 -5.264912 90)
			(size 0.3556 1.2192)
			(layers "F.Cu" "F.Mask" "F.Paste")
			(net "P5E_PEX1_STN0_TX_C_DN<2>")
		)
		(pad "B24" smd rect
			(at -1.27762 -4.664964 90)
			(size 0.3556 1.2192)
			(layers "F.Cu" "F.Mask" "F.Paste")
			(net "P5E_PEX1_STN0_TX_C_DP<2>")
		)
		(pad "B25" smd rect
			(at -1.27762 -4.065016 90)
			(size 0.3556 1.2192)
			(layers "F.Cu" "F.Mask" "F.Paste")
			(net "GND")
		)
		(pad "B26" smd rect
			(at -1.27762 -3.465068 90)
			(size 0.3556 1.2192)
			(layers "F.Cu" "F.Mask" "F.Paste")
			(net "P5E_PEX1_STN0_TX_C_DN<3>")
		)
		(pad "B27" smd rect
			(at -1.27762 -2.86512 90)
			(size 0.3556 1.2192)
			(layers "F.Cu" "F.Mask" "F.Paste")
			(net "P5E_PEX1_STN0_TX_C_DP<3>")
		)
		(pad "B28" smd rect
			(at -1.27762 -2.264918 90)
			(size 0.3556 1.2192)
			(layers "F.Cu" "F.Mask" "F.Paste")
			(net "GND")
		)
		(pad "B29" smd rect
			(at -1.27762 1.74498 90)
			(size 0.3556 1.2192)
			(layers "F.Cu" "F.Mask" "F.Paste")
			(net "GND")
		)
		(pad "B30" smd rect
			(at -1.27762 2.344928 90)
			(size 0.3556 1.2192)
			(layers "F.Cu" "F.Mask" "F.Paste")
			(net "P5E_PEX1_STN0_TX_C_DN<4>")
		)
		(pad "B31" smd rect
			(at -1.27762 2.944876 90)
			(size 0.3556 1.2192)
			(layers "F.Cu" "F.Mask" "F.Paste")
			(net "P5E_PEX1_STN0_TX_C_DP<4>")
		)
		(pad "B32" smd rect
			(at -1.27762 3.545078 90)
			(size 0.3556 1.2192)
			(layers "F.Cu" "F.Mask" "F.Paste")
			(net "GND")
		)
		(pad "B33" smd rect
			(at -1.27762 4.145026 90)
			(size 0.3556 1.2192)
			(layers "F.Cu" "F.Mask" "F.Paste")
			(net "P5E_PEX1_STN0_TX_C_DN<5>")
		)
		(pad "B34" smd rect
			(at -1.27762 4.744974 90)
			(size 0.3556 1.2192)
			(layers "F.Cu" "F.Mask" "F.Paste")
			(net "P5E_PEX1_STN0_TX_C_DP<5>")
		)
		(pad "B35" smd rect
			(at -1.27762 5.344922 90)
			(size 0.3556 1.2192)
			(layers "F.Cu" "F.Mask" "F.Paste")
			(net "GND")
		)
		(pad "B36" smd rect
			(at -1.27762 5.945124 90)
			(size 0.3556 1.2192)
			(layers "F.Cu" "F.Mask" "F.Paste")
			(net "P5E_PEX1_STN0_TX_C_DN<6>")
		)
		(pad "B37" smd rect
			(at -1.27762 6.545072 90)
			(size 0.3556 1.2192)
			(layers "F.Cu" "F.Mask" "F.Paste")
			(net "P5E_PEX1_STN0_TX_C_DP<6>")
		)
	)
)
